(kicad_pcb
	(version 20260206)
	(generator "pcbnew")
	(generator_version "10.0")
	(general
		(thickness 1.6)
		(legacy_teardrops no)
	)
	(paper "A4")
	(title_block
		(title "04192023_DAF0TMB3IC0_F0TG_MB_C_brd_V02_OCP.brd")
		(comment 1 "Grand Teton / footprint 3955 of 8354 (U25), pads 5008-5120 of 6102")
	)
	(layers
		(0 "F.Cu" signal "TOP")
		(4 "In1.Cu" signal "GND")
		(6 "In2.Cu" signal "IN1")
		(8 "In3.Cu" signal "GND1")
		(10 "In4.Cu" signal "IN2")
		(12 "In5.Cu" signal "GND2")
		(14 "In6.Cu" signal "IN3")
		(16 "In7.Cu" signal "GND3")
		(18 "In8.Cu" signal "VCC")
		(20 "In9.Cu" signal "VCC1")
		(22 "In10.Cu" signal "GND4")
		(24 "In11.Cu" signal "IN4")
		(26 "In12.Cu" signal "GND5")
		(28 "In13.Cu" signal "IN5")
		(30 "In14.Cu" signal "GND6")
		(32 "In15.Cu" signal "IN6")
		(34 "In16.Cu" signal "GND7")
		(2 "B.Cu" signal "BOTTOM")
		(9 "F.Adhes" user "F.Adhesive")
		(11 "B.Adhes" user "B.Adhesive")
		(13 "F.Paste" user "Package Geometry/Pastemask Top")
		(15 "B.Paste" user "Package Geometry/Pastemask Bottom")
		(5 "F.SilkS" user "Ref Des/Silkscreen Top")
		(7 "B.SilkS" user "Ref Des/Silkscreen Bottom")
		(1 "F.Mask" user "Board Geometry/Soldermask Top")
		(3 "B.Mask" user "Board Geometry/Soldermask Bottom")
		(17 "Dwgs.User" user "User.Drawings")
		(19 "Cmts.User" user "User.Comments")
		(21 "Eco1.User" user "User.Eco1")
		(23 "Eco2.User" user "User.Eco2")
		(25 "Edge.Cuts" user "Board Geometry/Outline")
		(27 "Margin" user)
		(31 "F.CrtYd" user "Package Geometry/Place Bound Top")
		(29 "B.CrtYd" user "Package Geometry/Place Bound Bottom")
		(35 "F.Fab" user "Ref Des/Assembly Top")
		(33 "B.Fab" user "Ref Des/Assembly Bottom")
	)
	(footprint ""
		(layer "F.Cu")
		(at 359.867962 -258.880102 180)
		(property "Reference" "U25"
			(at -45.78477 -62.086744 0)
			(unlocked yes)
			(layer "F.SilkS")
			(effects
				(font
					(size 0.7874 0.5842)
					(thickness 0.1524)
				)
			)
		)
		(property "Value" ""
			(at 0 0 180)
			(layer "F.Fab")
			(effects
				(font
					(size 1.27 1.27)
				)
			)
		)
		(duplicate_pad_numbers_are_jumpers no)
		(pad "E61" smd circle
			(at 21.299932 -33.56991 180)
			(size 0.450088 0.450088)
			(layers "F.Cu" "F.Mask" "F.Paste")
			(net "GND")
		)
		(pad "E62" smd circle
			(at 22.239986 -33.56991 180)
			(size 0.450088 0.450088)
			(layers "F.Cu" "F.Mask" "F.Paste")
			(net "GND")
		)
		(pad "E63" smd circle
			(at 23.18004 -33.56991 180)
			(size 0.450088 0.450088)
			(layers "F.Cu" "F.Mask" "F.Paste")
			(net "GND")
		)
		(pad "E64" smd circle
			(at 24.120094 -33.56991 180)
			(size 0.450088 0.450088)
			(layers "F.Cu" "F.Mask" "F.Paste")
			(net "M_B_CPU0_SA_DQ<0>")
		)
		(pad "E65" smd circle
			(at 25.059894 -33.56991 180)
			(size 0.450088 0.450088)
			(layers "F.Cu" "F.Mask" "F.Paste")
			(net "GND")
		)
		(pad "E66" smd circle
			(at 25.999948 -33.56991 180)
			(size 0.450088 0.450088)
			(layers "F.Cu" "F.Mask" "F.Paste")
			(net "GND")
		)
		(pad "E67" smd circle
			(at 26.940002 -33.56991 180)
			(size 0.450088 0.450088)
			(layers "F.Cu" "F.Mask" "F.Paste")
			(net "M_F_CPU0_SA_DQ<0>")
		)
		(pad "E68" smd circle
			(at 27.880056 -33.56991 180)
			(size 0.450088 0.450088)
			(layers "F.Cu" "F.Mask" "F.Paste")
			(net "GND")
		)
		(pad "E69" smd circle
			(at 28.82011 -33.56991 180)
			(size 0.450088 0.450088)
			(layers "F.Cu" "F.Mask" "F.Paste")
			(net "GND")
		)
		(pad "E70" smd circle
			(at 29.75991 -33.56991 180)
			(size 0.450088 0.450088)
			(layers "F.Cu" "F.Mask" "F.Paste")
			(net "GND")
		)
		(pad "E71" smd circle
			(at 30.699964 -33.56991 180)
			(size 0.450088 0.450088)
			(layers "F.Cu" "F.Mask" "F.Paste")
			(net "M_E_CPU0_SA_DQ<0>")
		)
		(pad "E72" smd circle
			(at 31.640018 -33.56991 180)
			(size 0.450088 0.450088)
			(layers "F.Cu" "F.Mask" "F.Paste")
			(net "GND")
		)
		(pad "E73" smd circle
			(at 32.580072 -33.56991 180)
			(size 0.450088 0.450088)
			(layers "F.Cu" "F.Mask" "F.Paste")
			(net "GND")
		)
		(pad "E74" smd circle
			(at 33.519872 -33.56991 180)
			(size 0.450088 0.450088)
			(layers "F.Cu" "F.Mask" "F.Paste")
			(net "M_A_CPU0_SA_DQ<0>")
		)
		(pad "E75" smd circle
			(at 34.459926 -33.56991 180)
			(size 0.450088 0.450088)
			(layers "F.Cu" "F.Mask" "F.Paste")
			(net "GND")
		)
		(pad "F2" smd circle
			(at -33.690052 -32.759904 180)
			(size 0.450088 0.450088)
			(layers "F.Cu" "F.Mask" "F.Paste")
			(net "M_G_CPU0_SA_DQ<2>")
		)
		(pad "F3" smd circle
			(at -32.749998 -32.759904 180)
			(size 0.450088 0.450088)
			(layers "F.Cu" "F.Mask" "F.Paste")
			(net "GND")
		)
		(pad "F4" smd circle
			(at -31.809944 -32.759904 180)
			(size 0.450088 0.450088)
			(layers "F.Cu" "F.Mask" "F.Paste")
			(net "M_G_CPU0_SA_DQ<1>")
		)
		(pad "F5" smd circle
			(at -30.86989 -32.759904 180)
			(size 0.450088 0.450088)
			(layers "F.Cu" "F.Mask" "F.Paste")
			(net "GND")
		)
		(pad "F6" smd circle
			(at -29.93009 -32.759904 180)
			(size 0.450088 0.450088)
			(layers "F.Cu" "F.Mask" "F.Paste")
			(net "M_K_CPU0_SA_DQ<2>")
		)
		(pad "F7" smd circle
			(at -28.990036 -32.759904 180)
			(size 0.450088 0.450088)
			(layers "F.Cu" "F.Mask" "F.Paste")
			(net "M_K_CPU0_SA_DQ<1>")
		)
		(pad "F8" smd circle
			(at -28.049982 -32.759904 180)
			(size 0.450088 0.450088)
			(layers "F.Cu" "F.Mask" "F.Paste")
			(net "GND")
		)
		(pad "F9" smd circle
			(at -27.109928 -32.759904 180)
			(size 0.450088 0.450088)
			(layers "F.Cu" "F.Mask" "F.Paste")
			(net "M_L_CPU0_SA_DQ<2>")
		)
		(pad "F10" smd circle
			(at -26.170128 -32.759904 180)
			(size 0.450088 0.450088)
			(layers "F.Cu" "F.Mask" "F.Paste")
			(net "GND")
		)
		(pad "F11" smd circle
			(at -25.230074 -32.759904 180)
			(size 0.450088 0.450088)
			(layers "F.Cu" "F.Mask" "F.Paste")
			(net "M_L_CPU0_SA_DQ<1>")
		)
		(pad "F12" smd circle
			(at -24.29002 -32.759904 180)
			(size 0.450088 0.450088)
			(layers "F.Cu" "F.Mask" "F.Paste")
			(net "GND")
		)
		(pad "F13" smd circle
			(at -23.349966 -32.759904 180)
			(size 0.450088 0.450088)
			(layers "F.Cu" "F.Mask" "F.Paste")
			(net "M_H_CPU0_SA_DQ<2>")
		)
		(pad "F14" smd circle
			(at -22.409912 -32.759904 180)
			(size 0.450088 0.450088)
			(layers "F.Cu" "F.Mask" "F.Paste")
			(net "M_H_CPU0_SA_DQ<1>")
		)
		(pad "F15" smd circle
			(at -21.470112 -32.759904 180)
			(size 0.450088 0.450088)
			(layers "F.Cu" "F.Mask" "F.Paste")
			(net "GND")
		)
		(pad "F16" smd circle
			(at -20.530058 -32.759904 180)
			(size 0.450088 0.450088)
			(layers "F.Cu" "F.Mask" "F.Paste")
			(net "M_J_CPU0_SA_DQ<2>")
		)
		(pad "F17" smd circle
			(at -19.590004 -32.759904 180)
			(size 0.450088 0.450088)
			(layers "F.Cu" "F.Mask" "F.Paste")
			(net "GND")
		)
		(pad "F18" smd circle
			(at -18.64995 -32.759904 180)
			(size 0.450088 0.450088)
			(layers "F.Cu" "F.Mask" "F.Paste")
			(net "M_J_CPU0_SA_DQ<1>")
		)
		(pad "F19" smd circle
			(at -17.709896 -32.759904 180)
			(size 0.450088 0.450088)
			(layers "F.Cu" "F.Mask" "F.Paste")
			(net "GND")
		)
		(pad "F20" smd circle
			(at -16.770096 -32.759904 180)
			(size 0.450088 0.450088)
			(layers "F.Cu" "F.Mask" "F.Paste")
			(net "M_I_CPU0_SA_DQ<2>")
		)
		(pad "F21" smd circle
			(at -15.830042 -32.759904 180)
			(size 0.450088 0.450088)
			(layers "F.Cu" "F.Mask" "F.Paste")
			(net "M_I_CPU0_SA_DQ<1>")
		)
		(pad "F22" smd circle
			(at -14.889988 -32.759904 180)
			(size 0.450088 0.450088)
			(layers "F.Cu" "F.Mask" "F.Paste")
			(net "PVDDCR_CPU0_P0")
		)
		(pad "F23" smd circle
			(at -13.949934 -32.759904 180)
			(size 0.450088 0.450088)
			(layers "F.Cu" "F.Mask" "F.Paste")
			(net "GND")
		)
		(pad "F24" smd circle
			(at -13.00988 -32.759904 180)
			(size 0.450088 0.450088)
			(layers "F.Cu" "F.Mask" "F.Paste")
			(net "GND")
		)
		(pad "F25" smd circle
			(at -12.07008 -32.759904 180)
			(size 0.450088 0.450088)
			(layers "F.Cu" "F.Mask" "F.Paste")
			(net "PVDDCR_CPU0_P0")
		)
		(pad "F26" smd circle
			(at -11.130026 -32.759904 180)
			(size 0.450088 0.450088)
			(layers "F.Cu" "F.Mask" "F.Paste")
			(net "GND")
		)
		(pad "F27" smd circle
			(at -10.189972 -32.759904 180)
			(size 0.450088 0.450088)
			(layers "F.Cu" "F.Mask" "F.Paste")
			(net "GND")
		)
		(pad "F28" smd circle
			(at -9.249918 -32.759904 180)
			(size 0.450088 0.450088)
			(layers "F.Cu" "F.Mask" "F.Paste")
			(net "PVDDCR_CPU0_P0")
		)
		(pad "F29" smd circle
			(at -8.310118 -32.759904 180)
			(size 0.450088 0.450088)
			(layers "F.Cu" "F.Mask" "F.Paste")
			(net "GND")
		)
		(pad "F30" smd circle
			(at -7.370064 -32.759904 180)
			(size 0.450088 0.450088)
			(layers "F.Cu" "F.Mask" "F.Paste")
			(net "GND")
		)
		(pad "F31" smd circle
			(at -6.43001 -32.759904 180)
			(size 0.450088 0.450088)
			(layers "F.Cu" "F.Mask" "F.Paste")
			(net "PVDDCR_CPU0_P0")
		)
		(pad "F32" smd circle
			(at -5.489956 -32.759904 180)
			(size 0.450088 0.450088)
			(layers "F.Cu" "F.Mask" "F.Paste")
			(net "GND")
		)
		(pad "F33" smd circle
			(at -4.549902 -32.759904 180)
			(size 0.450088 0.450088)
			(layers "F.Cu" "F.Mask" "F.Paste")
			(net "GND")
		)
		(pad "F34" smd circle
			(at -3.610102 -32.759904 180)
			(size 0.450088 0.450088)
			(layers "F.Cu" "F.Mask" "F.Paste")
			(net "PVDDCR_CPU0_P0")
		)
		(pad "F35" smd circle
			(at -2.670048 -32.759904 180)
			(size 0.450088 0.450088)
			(layers "F.Cu" "F.Mask" "F.Paste")
			(net "GND")
		)
		(pad "F36" smd circle
			(at -1.729994 -32.759904 180)
			(size 0.450088 0.450088)
			(layers "F.Cu" "F.Mask" "F.Paste")
			(net "GND")
		)
		(pad "F37" smd circle
			(at -0.78994 -32.759904 180)
			(size 0.450088 0.450088)
			(layers "F.Cu" "F.Mask" "F.Paste")
			(net "GND")
		)
		(pad "F39" smd circle
			(at 1.089914 -32.759904 180)
			(size 0.450088 0.450088)
			(layers "F.Cu" "F.Mask" "F.Paste")
			(net "GND")
		)
		(pad "F40" smd circle
			(at 2.029968 -32.759904 180)
			(size 0.450088 0.450088)
			(layers "F.Cu" "F.Mask" "F.Paste")
			(net "GND")
		)
		(pad "F41" smd circle
			(at 2.970022 -32.759904 180)
			(size 0.450088 0.450088)
			(layers "F.Cu" "F.Mask" "F.Paste")
			(net "GND")
		)
		(pad "F42" smd circle
			(at 3.910076 -32.759904 180)
			(size 0.450088 0.450088)
			(layers "F.Cu" "F.Mask" "F.Paste")
			(net "PVDDCR_CPU0_P0")
		)
		(pad "F43" smd circle
			(at 4.849876 -32.759904 180)
			(size 0.450088 0.450088)
			(layers "F.Cu" "F.Mask" "F.Paste")
			(net "GND")
		)
		(pad "F44" smd circle
			(at 5.78993 -32.759904 180)
			(size 0.450088 0.450088)
			(layers "F.Cu" "F.Mask" "F.Paste")
			(net "GND")
		)
		(pad "F45" smd circle
			(at 6.729984 -32.759904 180)
			(size 0.450088 0.450088)
			(layers "F.Cu" "F.Mask" "F.Paste")
			(net "PVDDCR_CPU0_P0")
		)
		(pad "F46" smd circle
			(at 7.670038 -32.759904 180)
			(size 0.450088 0.450088)
			(layers "F.Cu" "F.Mask" "F.Paste")
			(net "GND")
		)
		(pad "F47" smd circle
			(at 8.610092 -32.759904 180)
			(size 0.450088 0.450088)
			(layers "F.Cu" "F.Mask" "F.Paste")
			(net "GND")
		)
		(pad "F48" smd circle
			(at 9.549892 -32.759904 180)
			(size 0.450088 0.450088)
			(layers "F.Cu" "F.Mask" "F.Paste")
			(net "PVDDCR_CPU0_P0")
		)
		(pad "F49" smd circle
			(at 10.489946 -32.759904 180)
			(size 0.450088 0.450088)
			(layers "F.Cu" "F.Mask" "F.Paste")
			(net "GND")
		)
		(pad "F50" smd circle
			(at 11.43 -32.759904 180)
			(size 0.450088 0.450088)
			(layers "F.Cu" "F.Mask" "F.Paste")
			(net "GND")
		)
		(pad "F51" smd circle
			(at 12.370054 -32.759904 180)
			(size 0.450088 0.450088)
			(layers "F.Cu" "F.Mask" "F.Paste")
			(net "PVDDCR_CPU0_P0")
		)
		(pad "F52" smd circle
			(at 13.310108 -32.759904 180)
			(size 0.450088 0.450088)
			(layers "F.Cu" "F.Mask" "F.Paste")
			(net "GND")
		)
		(pad "F53" smd circle
			(at 14.249908 -32.759904 180)
			(size 0.450088 0.450088)
			(layers "F.Cu" "F.Mask" "F.Paste")
			(net "GND")
		)
		(pad "F54" smd circle
			(at 15.189962 -32.759904 180)
			(size 0.450088 0.450088)
			(layers "F.Cu" "F.Mask" "F.Paste")
			(net "PVDDCR_CPU0_P0")
		)
		(pad "F55" smd circle
			(at 16.130016 -32.759904 180)
			(size 0.450088 0.450088)
			(layers "F.Cu" "F.Mask" "F.Paste")
			(net "M_C_CPU0_SA_DQ<1>")
		)
		(pad "F56" smd circle
			(at 17.07007 -32.759904 180)
			(size 0.450088 0.450088)
			(layers "F.Cu" "F.Mask" "F.Paste")
			(net "M_C_CPU0_SA_DQ<2>")
		)
		(pad "F57" smd circle
			(at 18.010124 -32.759904 180)
			(size 0.450088 0.450088)
			(layers "F.Cu" "F.Mask" "F.Paste")
			(net "GND")
		)
		(pad "F58" smd circle
			(at 18.949924 -32.759904 180)
			(size 0.450088 0.450088)
			(layers "F.Cu" "F.Mask" "F.Paste")
			(net "M_D_CPU0_SA_DQ<1>")
		)
		(pad "F59" smd circle
			(at 19.889978 -32.759904 180)
			(size 0.450088 0.450088)
			(layers "F.Cu" "F.Mask" "F.Paste")
			(net "GND")
		)
		(pad "F60" smd circle
			(at 20.830032 -32.759904 180)
			(size 0.450088 0.450088)
			(layers "F.Cu" "F.Mask" "F.Paste")
			(net "M_D_CPU0_SA_DQ<2>")
		)
		(pad "F61" smd circle
			(at 21.770086 -32.759904 180)
			(size 0.450088 0.450088)
			(layers "F.Cu" "F.Mask" "F.Paste")
			(net "GND")
		)
		(pad "F62" smd circle
			(at 22.709886 -32.759904 180)
			(size 0.450088 0.450088)
			(layers "F.Cu" "F.Mask" "F.Paste")
			(net "M_B_CPU0_SA_DQ<1>")
		)
		(pad "F63" smd circle
			(at 23.64994 -32.759904 180)
			(size 0.450088 0.450088)
			(layers "F.Cu" "F.Mask" "F.Paste")
			(net "M_B_CPU0_SA_DQ<2>")
		)
		(pad "F64" smd circle
			(at 24.589994 -32.759904 180)
			(size 0.450088 0.450088)
			(layers "F.Cu" "F.Mask" "F.Paste")
			(net "GND")
		)
		(pad "F65" smd circle
			(at 25.530048 -32.759904 180)
			(size 0.450088 0.450088)
			(layers "F.Cu" "F.Mask" "F.Paste")
			(net "M_F_CPU0_SA_DQ<1>")
		)
		(pad "F66" smd circle
			(at 26.470102 -32.759904 180)
			(size 0.450088 0.450088)
			(layers "F.Cu" "F.Mask" "F.Paste")
			(net "GND")
		)
		(pad "F67" smd circle
			(at 27.409902 -32.759904 180)
			(size 0.450088 0.450088)
			(layers "F.Cu" "F.Mask" "F.Paste")
			(net "M_F_CPU0_SA_DQ<2>")
		)
		(pad "F68" smd circle
			(at 28.349956 -32.759904 180)
			(size 0.450088 0.450088)
			(layers "F.Cu" "F.Mask" "F.Paste")
			(net "GND")
		)
		(pad "F69" smd circle
			(at 29.29001 -32.759904 180)
			(size 0.450088 0.450088)
			(layers "F.Cu" "F.Mask" "F.Paste")
			(net "M_E_CPU0_SA_DQ<1>")
		)
		(pad "F70" smd circle
			(at 30.230064 -32.759904 180)
			(size 0.450088 0.450088)
			(layers "F.Cu" "F.Mask" "F.Paste")
			(net "M_E_CPU0_SA_DQ<2>")
		)
		(pad "F71" smd circle
			(at 31.170118 -32.759904 180)
			(size 0.450088 0.450088)
			(layers "F.Cu" "F.Mask" "F.Paste")
			(net "GND")
		)
		(pad "F72" smd circle
			(at 32.109918 -32.759904 180)
			(size 0.450088 0.450088)
			(layers "F.Cu" "F.Mask" "F.Paste")
			(net "M_A_CPU0_SA_DQ<1>")
		)
		(pad "F73" smd circle
			(at 33.049972 -32.759904 180)
			(size 0.450088 0.450088)
			(layers "F.Cu" "F.Mask" "F.Paste")
			(net "GND")
		)
		(pad "F74" smd circle
			(at 33.990026 -32.759904 180)
			(size 0.450088 0.450088)
			(layers "F.Cu" "F.Mask" "F.Paste")
			(net "M_A_CPU0_SA_DQ<2>")
		)
		(pad "G1" smd circle
			(at -34.159952 -31.949898 180)
			(size 0.450088 0.450088)
			(layers "F.Cu" "F.Mask" "F.Paste")
			(net "GND")
		)
		(pad "G2" smd circle
			(at -33.219898 -31.949898 180)
			(size 0.450088 0.450088)
			(layers "F.Cu" "F.Mask" "F.Paste")
			(net "M_G_CPU0_SA_DQS_DP<0>")
		)
		(pad "G3" smd circle
			(at -32.280098 -31.949898 180)
			(size 0.450088 0.450088)
			(layers "F.Cu" "F.Mask" "F.Paste")
			(net "M_G_CPU0_SA_DQ<3>")
		)
		(pad "G4" smd circle
			(at -31.340044 -31.949898 180)
			(size 0.450088 0.450088)
			(layers "F.Cu" "F.Mask" "F.Paste")
			(net "GND")
		)
		(pad "G5" smd circle
			(at -30.39999 -31.949898 180)
			(size 0.450088 0.450088)
			(layers "F.Cu" "F.Mask" "F.Paste")
			(net "M_K_CPU0_SA_DQS_DP<0>")
		)
		(pad "G6" smd circle
			(at -29.459936 -31.949898 180)
			(size 0.450088 0.450088)
			(layers "F.Cu" "F.Mask" "F.Paste")
			(net "GND")
		)
		(pad "G7" smd circle
			(at -28.519882 -31.949898 180)
			(size 0.450088 0.450088)
			(layers "F.Cu" "F.Mask" "F.Paste")
			(net "M_K_CPU0_SA_DQ<3>")
		)
		(pad "G8" smd circle
			(at -27.580082 -31.949898 180)
			(size 0.450088 0.450088)
			(layers "F.Cu" "F.Mask" "F.Paste")
			(net "GND")
		)
		(pad "G9" smd circle
			(at -26.640028 -31.949898 180)
			(size 0.450088 0.450088)
			(layers "F.Cu" "F.Mask" "F.Paste")
			(net "M_L_CPU0_SA_DQS_DP<0>")
		)
		(pad "G10" smd circle
			(at -25.699974 -31.949898 180)
			(size 0.450088 0.450088)
			(layers "F.Cu" "F.Mask" "F.Paste")
			(net "M_L_CPU0_SA_DQ<3>")
		)
		(pad "G11" smd circle
			(at -24.75992 -31.949898 180)
			(size 0.450088 0.450088)
			(layers "F.Cu" "F.Mask" "F.Paste")
			(net "GND")
		)
		(pad "G12" smd circle
			(at -23.82012 -31.949898 180)
			(size 0.450088 0.450088)
			(layers "F.Cu" "F.Mask" "F.Paste")
			(net "M_H_CPU0_SA_DQS_DP<0>")
		)
		(pad "G13" smd circle
			(at -22.880066 -31.949898 180)
			(size 0.450088 0.450088)
			(layers "F.Cu" "F.Mask" "F.Paste")
			(net "GND")
		)
		(pad "G14" smd circle
			(at -21.940012 -31.949898 180)
			(size 0.450088 0.450088)
			(layers "F.Cu" "F.Mask" "F.Paste")
			(net "M_H_CPU0_SA_DQ<3>")
		)
		(pad "G15" smd circle
			(at -20.999958 -31.949898 180)
			(size 0.450088 0.450088)
			(layers "F.Cu" "F.Mask" "F.Paste")
			(net "GND")
		)
		(pad "G16" smd circle
			(at -20.059904 -31.949898 180)
			(size 0.450088 0.450088)
			(layers "F.Cu" "F.Mask" "F.Paste")
			(net "M_J_CPU0_SA_DQS_DP<0>")
		)
		(pad "G17" smd circle
			(at -19.120104 -31.949898 180)
			(size 0.450088 0.450088)
			(layers "F.Cu" "F.Mask" "F.Paste")
			(net "M_J_CPU0_SA_DQ<3>")
		)
		(pad "G18" smd circle
			(at -18.18005 -31.949898 180)
			(size 0.450088 0.450088)
			(layers "F.Cu" "F.Mask" "F.Paste")
			(net "GND")
		)
		(pad "G19" smd circle
			(at -17.239996 -31.949898 180)
			(size 0.450088 0.450088)
			(layers "F.Cu" "F.Mask" "F.Paste")
			(net "M_I_CPU0_SA_DQS_DP<0>")
		)
		(pad "G20" smd circle
			(at -16.299942 -31.949898 180)
			(size 0.450088 0.450088)
			(layers "F.Cu" "F.Mask" "F.Paste")
			(net "GND")
		)
		(pad "G21" smd circle
			(at -15.359888 -31.949898 180)
			(size 0.450088 0.450088)
			(layers "F.Cu" "F.Mask" "F.Paste")
			(net "M_I_CPU0_SA_DQ<3>")
		)
		(pad "G22" smd circle
			(at -14.420088 -31.949898 180)
			(size 0.450088 0.450088)
			(layers "F.Cu" "F.Mask" "F.Paste")
			(net "GND")
		)
		(pad "G23" smd circle
			(at -13.480034 -31.949898 180)
			(size 0.450088 0.450088)
			(layers "F.Cu" "F.Mask" "F.Paste")
			(net "GMI_CPU0_G2_CPU1_G0_TX_DP<2>")
		)
		(pad "G24" smd circle
			(at -12.53998 -31.949898 180)
			(size 0.450088 0.450088)
			(layers "F.Cu" "F.Mask" "F.Paste")
			(net "GMI_CPU0_G2_CPU1_G0_TX_DN<2>")
		)
		(pad "G25" smd circle
			(at -11.599926 -31.949898 180)
			(size 0.450088 0.450088)
			(layers "F.Cu" "F.Mask" "F.Paste")
			(net "GND")
		)
		(pad "G26" smd circle
			(at -10.659872 -31.949898 180)
			(size 0.450088 0.450088)
			(layers "F.Cu" "F.Mask" "F.Paste")
			(net "GMI_CPU0_G2_CPU1_G0_TX_DP<5>")
		)
	)
)
